(kicad_pcb
	(version 20260206)
	(generator "pcbnew")
	(generator_version "10.0")
	(general
		(thickness 1.6)
		(legacy_teardrops no)
	)
	(paper "A4")
	(title_block
		(title "01162023_DA0F0TEBIF0_F0T_Expander_BD_F_brd_V02_OCP.brd")
		(comment 1 "Grand Teton / footprints 2454-2458 of 9728")
	)
	(layers
		(0 "F.Cu" signal "TOP")
		(4 "In1.Cu" signal "GND")
		(6 "In2.Cu" signal "VCC")
		(8 "In3.Cu" signal "VCC1")
		(10 "In4.Cu" signal "GND1")
		(12 "In5.Cu" signal "IN1")
		(14 "In6.Cu" signal "GND2")
		(16 "In7.Cu" signal "IN2")
		(18 "In8.Cu" signal "GND3")
		(20 "In9.Cu" signal "IN3")
		(22 "In10.Cu" signal "GND4")
		(24 "In11.Cu" signal "IN4")
		(26 "In12.Cu" signal "GND5")
		(28 "In13.Cu" signal "IN5")
		(30 "In14.Cu" signal "GND6")
		(32 "In15.Cu" signal "IN6")
		(34 "In16.Cu" signal "GND7")
		(2 "B.Cu" signal "BOTTOM")
		(9 "F.Adhes" user "F.Adhesive")
		(11 "B.Adhes" user "B.Adhesive")
		(13 "F.Paste" user "Package Geometry/Pastemask Top")
		(15 "B.Paste" user "Package Geometry/Pastemask Bottom")
		(5 "F.SilkS" user "Ref Des/Silkscreen Top")
		(7 "B.SilkS" user "Ref Des/Silkscreen Bottom")
		(1 "F.Mask" user "Board Geometry/Soldermask Top")
		(3 "B.Mask" user "Board Geometry/Soldermask Bottom")
		(17 "Dwgs.User" user "User.Drawings")
		(19 "Cmts.User" user "User.Comments")
		(21 "Eco1.User" user "User.Eco1")
		(23 "Eco2.User" user "User.Eco2")
		(25 "Edge.Cuts" user "Board Geometry/Outline")
		(27 "Margin" user)
		(31 "F.CrtYd" user "Package Geometry/Place Bound Top")
		(29 "B.CrtYd" user "Package Geometry/Place Bound Bottom")
		(35 "F.Fab" user "Ref Des/Assembly Top")
		(33 "B.Fab" user "Ref Des/Assembly Bottom")
	)
	(footprint ""
		(layer "F.Cu")
		(at 183.847994 -188.101224 -90)
		(property "Reference" "C2093"
			(at 0 0 270)
			(layer "F.SilkS")
			(hide yes)
			(effects
				(font
					(size 1.27 1.27)
				)
			)
		)
		(property "Value" ""
			(at 0 0 270)
			(layer "F.Fab")
			(effects
				(font
					(size 1.27 1.27)
				)
			)
		)
		(duplicate_pad_numbers_are_jumpers no)
		(fp_line
			(start -0.7874 0.4064)
			(end -0.7874 -0.4064)
			(stroke
				(width 0.1524)
				(type default)
			)
			(layer "F.SilkS")
		)
		(fp_line
			(start 0.7874 0.4064)
			(end -0.7874 0.4064)
			(stroke
				(width 0.1524)
				(type default)
			)
			(layer "F.SilkS")
		)
		(fp_line
			(start -0.7874 -0.4064)
			(end 0.7874 -0.4064)
			(stroke
				(width 0.1524)
				(type default)
			)
			(layer "F.SilkS")
		)
		(fp_line
			(start 0.7874 -0.4064)
			(end 0.7874 0.4064)
			(stroke
				(width 0.1524)
				(type default)
			)
			(layer "F.SilkS")
		)
		(fp_line
			(start -0.67945 0.3048)
			(end -0.67945 -0.305054)
			(stroke
				(width 0.1)
				(type default)
			)
			(layer "F.Fab")
		)
		(fp_line
			(start -0.12065 0.3048)
			(end -0.67945 0.3048)
			(stroke
				(width 0.1)
				(type default)
			)
			(layer "F.Fab")
		)
		(fp_line
			(start 0.120396 0.3048)
			(end 0.120396 0.2794)
			(stroke
				(width 0.1)
				(type default)
			)
			(layer "F.Fab")
		)
		(fp_line
			(start 0.67945 0.3048)
			(end 0.120396 0.3048)
			(stroke
				(width 0.1)
				(type default)
			)
			(layer "F.Fab")
		)
		(fp_line
			(start -0.12065 0.2794)
			(end -0.12065 0.3048)
			(stroke
				(width 0.1)
				(type default)
			)
			(layer "F.Fab")
		)
		(fp_line
			(start 0.120396 0.2794)
			(end -0.12065 0.2794)
			(stroke
				(width 0.1)
				(type default)
			)
			(layer "F.Fab")
		)
		(fp_line
			(start -0.12065 -0.2794)
			(end 0.12065 -0.2794)
			(stroke
				(width 0.1)
				(type default)
			)
			(layer "F.Fab")
		)
		(fp_line
			(start 0.12065 -0.2794)
			(end 0.12065 -0.3048)
			(stroke
				(width 0.1)
				(type default)
			)
			(layer "F.Fab")
		)
		(fp_line
			(start 0.12065 -0.3048)
			(end 0.67945 -0.3048)
			(stroke
				(width 0.1)
				(type default)
			)
			(layer "F.Fab")
		)
		(fp_line
			(start 0.67945 -0.3048)
			(end 0.67945 0.3048)
			(stroke
				(width 0.1)
				(type default)
			)
			(layer "F.Fab")
		)
		(fp_line
			(start -0.67945 -0.305054)
			(end -0.12065 -0.305054)
			(stroke
				(width 0.1)
				(type default)
			)
			(layer "F.Fab")
		)
		(fp_line
			(start -0.12065 -0.305054)
			(end -0.12065 -0.2794)
			(stroke
				(width 0.1)
				(type default)
			)
			(layer "F.Fab")
		)
		(pad "1" smd circle
			(at -0.40005 0 270)
			(size 0 0)
			(layers "F.Cu" "F.Mask" "F.Paste")
			(net "GND")
		)
		(pad "2" smd circle
			(at 0.40005 0 270)
			(size 0 0)
			(layers "F.Cu" "F.Mask" "F.Paste")
			(net "P3V3_AUX")
		)
	)
	(footprint ""
		(layer "F.Cu")
		(at 378.18822 -260.84911 -90)
		(property "Reference" "C3555"
			(at 0 0 270)
			(layer "F.SilkS")
			(hide yes)
			(effects
				(font
					(size 1.27 1.27)
				)
			)
		)
		(property "Value" ""
			(at 0 0 270)
			(layer "F.Fab")
			(effects
				(font
					(size 1.27 1.27)
				)
			)
		)
		(duplicate_pad_numbers_are_jumpers no)
		(fp_line
			(start -1.2954 0.5842)
			(end -1.2954 -0.5842)
			(stroke
				(width 0.1524)
				(type default)
			)
			(layer "F.SilkS")
		)
		(fp_line
			(start 1.2954 0.5842)
			(end -1.2954 0.5842)
			(stroke
				(width 0.1524)
				(type default)
			)
			(layer "F.SilkS")
		)
		(fp_line
			(start -1.2954 -0.5842)
			(end 1.2954 -0.5842)
			(stroke
				(width 0.1524)
				(type default)
			)
			(layer "F.SilkS")
		)
		(fp_line
			(start 1.2954 -0.5842)
			(end 1.2954 0.5842)
			(stroke
				(width 0.1524)
				(type default)
			)
			(layer "F.SilkS")
		)
		(fp_line
			(start -0.8636 0.4572)
			(end -0.8636 0.4064)
			(stroke
				(width 0.1)
				(type default)
			)
			(layer "F.Fab")
		)
		(fp_line
			(start 0.8636 0.4572)
			(end -0.8636 0.4572)
			(stroke
				(width 0.1)
				(type default)
			)
			(layer "F.Fab")
		)
		(fp_line
			(start -1.1938 0.4064)
			(end -1.1938 -0.4064)
			(stroke
				(width 0.1)
				(type default)
			)
			(layer "F.Fab")
		)
		(fp_line
			(start -0.8636 0.4064)
			(end -1.1938 0.4064)
			(stroke
				(width 0.1)
				(type default)
			)
			(layer "F.Fab")
		)
		(fp_line
			(start 0.8636 0.4064)
			(end 0.8636 0.4572)
			(stroke
				(width 0.1)
				(type default)
			)
			(layer "F.Fab")
		)
		(fp_line
			(start 1.1938 0.4064)
			(end 0.8636 0.4064)
			(stroke
				(width 0.1)
				(type default)
			)
			(layer "F.Fab")
		)
		(fp_line
			(start -1.1938 -0.4064)
			(end -0.8636 -0.4064)
			(stroke
				(width 0.1)
				(type default)
			)
			(layer "F.Fab")
		)
		(fp_line
			(start -0.8636 -0.4064)
			(end -0.8636 -0.4572)
			(stroke
				(width 0.1)
				(type default)
			)
			(layer "F.Fab")
		)
		(fp_line
			(start 0.8636 -0.4064)
			(end 1.1938 -0.4064)
			(stroke
				(width 0.1)
				(type default)
			)
			(layer "F.Fab")
		)
		(fp_line
			(start 1.1938 -0.4064)
			(end 1.1938 0.4064)
			(stroke
				(width 0.1)
				(type default)
			)
			(layer "F.Fab")
		)
		(fp_line
			(start -0.8636 -0.4572)
			(end 0.8636 -0.4572)
			(stroke
				(width 0.1)
				(type default)
			)
			(layer "F.Fab")
		)
		(fp_line
			(start 0.8636 -0.4572)
			(end 0.8636 -0.4064)
			(stroke
				(width 0.1)
				(type default)
			)
			(layer "F.Fab")
		)
		(pad "1" smd rect
			(at -0.7366 0 180)
			(size 0.7112 0.8128)
			(layers "F.Cu" "F.Mask" "F.Paste")
			(net "P1V8_PLL0_PEX3")
		)
		(pad "2" smd rect
			(at 0.7366 0 180)
			(size 0.7112 0.8128)
			(layers "F.Cu" "F.Mask" "F.Paste")
			(net "GND")
		)
	)
	(footprint ""
		(layer "F.Cu")
		(at 270.799814 -154.327352 180)
		(property "Reference" "R230"
			(at 0 0 180)
			(layer "F.SilkS")
			(hide yes)
			(effects
				(font
					(size 1.27 1.27)
				)
			)
		)
		(property "Value" ""
			(at 0 0 180)
			(layer "F.Fab")
			(effects
				(font
					(size 1.27 1.27)
				)
			)
		)
		(duplicate_pad_numbers_are_jumpers no)
		(fp_line
			(start 0.7874 0.4064)
			(end -0.7874 0.4064)
			(stroke
				(width 0.1524)
				(type default)
			)
			(layer "F.SilkS")
		)
		(fp_line
			(start 0.7874 -0.4064)
			(end 0.7874 0.4064)
			(stroke
				(width 0.1524)
				(type default)
			)
			(layer "F.SilkS")
		)
		(fp_line
			(start -0.7874 0.4064)
			(end -0.7874 -0.4064)
			(stroke
				(width 0.1524)
				(type default)
			)
			(layer "F.SilkS")
		)
		(fp_line
			(start -0.7874 -0.4064)
			(end 0.7874 -0.4064)
			(stroke
				(width 0.1524)
				(type default)
			)
			(layer "F.SilkS")
		)
		(fp_line
			(start 0.67945 0.3048)
			(end 0.120396 0.3048)
			(stroke
				(width 0.1)
				(type default)
			)
			(layer "F.Fab")
		)
		(fp_line
			(start 0.67945 -0.3048)
			(end 0.67945 0.3048)
			(stroke
				(width 0.1)
				(type default)
			)
			(layer "F.Fab")
		)
		(fp_line
			(start 0.12065 -0.2794)
			(end 0.12065 -0.3048)
			(stroke
				(width 0.1)
				(type default)
			)
			(layer "F.Fab")
		)
		(fp_line
			(start 0.12065 -0.3048)
			(end 0.67945 -0.3048)
			(stroke
				(width 0.1)
				(type default)
			)
			(layer "F.Fab")
		)
		(fp_line
			(start 0.120396 0.3048)
			(end 0.120396 0.2794)
			(stroke
				(width 0.1)
				(type default)
			)
			(layer "F.Fab")
		)
		(fp_line
			(start 0.120396 0.2794)
			(end -0.12065 0.2794)
			(stroke
				(width 0.1)
				(type default)
			)
			(layer "F.Fab")
		)
		(fp_line
			(start -0.12065 0.3048)
			(end -0.67945 0.3048)
			(stroke
				(width 0.1)
				(type default)
			)
			(layer "F.Fab")
		)
		(fp_line
			(start -0.12065 0.2794)
			(end -0.12065 0.3048)
			(stroke
				(width 0.1)
				(type default)
			)
			(layer "F.Fab")
		)
		(fp_line
			(start -0.12065 -0.2794)
			(end 0.12065 -0.2794)
			(stroke
				(width 0.1)
				(type default)
			)
			(layer "F.Fab")
		)
		(fp_line
			(start -0.12065 -0.305054)
			(end -0.12065 -0.2794)
			(stroke
				(width 0.1)
				(type default)
			)
			(layer "F.Fab")
		)
		(fp_line
			(start -0.67945 0.3048)
			(end -0.67945 -0.305054)
			(stroke
				(width 0.1)
				(type default)
			)
			(layer "F.Fab")
		)
		(fp_line
			(start -0.67945 -0.305054)
			(end -0.12065 -0.305054)
			(stroke
				(width 0.1)
				(type default)
			)
			(layer "F.Fab")
		)
		(pad "1" smd circle
			(at -0.40005 0 180)
			(size 0 0)
			(layers "F.Cu" "F.Mask" "F.Paste")
			(net "NIC4_SLOT_ID0")
		)
		(pad "2" smd circle
			(at 0.40005 0 180)
			(size 0 0)
			(layers "F.Cu" "F.Mask" "F.Paste")
			(net "GND")
		)
	)
	(footprint ""
		(layer "F.Cu")
		(at 359.016808 -162.003994 90)
		(property "Reference" "PC831"
			(at 0 0 90)
			(layer "F.SilkS")
			(hide yes)
			(effects
				(font
					(size 1.27 1.27)
				)
			)
		)
		(property "Value" ""
			(at 0 0 90)
			(layer "F.Fab")
			(effects
				(font
					(size 1.27 1.27)
				)
			)
		)
		(duplicate_pad_numbers_are_jumpers no)
		(fp_line
			(start 0.7874 -0.4064)
			(end 0.7874 0.4064)
			(stroke
				(width 0.1524)
				(type default)
			)
			(layer "F.SilkS")
		)
		(fp_line
			(start -0.7874 -0.4064)
			(end 0.7874 -0.4064)
			(stroke
				(width 0.1524)
				(type default)
			)
			(layer "F.SilkS")
		)
		(fp_line
			(start 0.7874 0.4064)
			(end -0.7874 0.4064)
			(stroke
				(width 0.1524)
				(type default)
			)
			(layer "F.SilkS")
		)
		(fp_line
			(start -0.7874 0.4064)
			(end -0.7874 -0.4064)
			(stroke
				(width 0.1524)
				(type default)
			)
			(layer "F.SilkS")
		)
		(fp_line
			(start -0.12065 -0.305054)
			(end -0.12065 -0.2794)
			(stroke
				(width 0.1)
				(type default)
			)
			(layer "F.Fab")
		)
		(fp_line
			(start -0.67945 -0.305054)
			(end -0.12065 -0.305054)
			(stroke
				(width 0.1)
				(type default)
			)
			(layer "F.Fab")
		)
		(fp_line
			(start 0.67945 -0.3048)
			(end 0.67945 0.3048)
			(stroke
				(width 0.1)
				(type default)
			)
			(layer "F.Fab")
		)
		(fp_line
			(start 0.12065 -0.3048)
			(end 0.67945 -0.3048)
			(stroke
				(width 0.1)
				(type default)
			)
			(layer "F.Fab")
		)
		(fp_line
			(start 0.12065 -0.2794)
			(end 0.12065 -0.3048)
			(stroke
				(width 0.1)
				(type default)
			)
			(layer "F.Fab")
		)
		(fp_line
			(start -0.12065 -0.2794)
			(end 0.12065 -0.2794)
			(stroke
				(width 0.1)
				(type default)
			)
			(layer "F.Fab")
		)
		(fp_line
			(start 0.120396 0.2794)
			(end -0.12065 0.2794)
			(stroke
				(width 0.1)
				(type default)
			)
			(layer "F.Fab")
		)
		(fp_line
			(start -0.12065 0.2794)
			(end -0.12065 0.3048)
			(stroke
				(width 0.1)
				(type default)
			)
			(layer "F.Fab")
		)
		(fp_line
			(start 0.67945 0.3048)
			(end 0.120396 0.3048)
			(stroke
				(width 0.1)
				(type default)
			)
			(layer "F.Fab")
		)
		(fp_line
			(start 0.120396 0.3048)
			(end 0.120396 0.2794)
			(stroke
				(width 0.1)
				(type default)
			)
			(layer "F.Fab")
		)
		(fp_line
			(start -0.12065 0.3048)
			(end -0.67945 0.3048)
			(stroke
				(width 0.1)
				(type default)
			)
			(layer "F.Fab")
		)
		(fp_line
			(start -0.67945 0.3048)
			(end -0.67945 -0.305054)
			(stroke
				(width 0.1)
				(type default)
			)
			(layer "F.Fab")
		)
		(pad "1" smd circle
			(at -0.40005 0 90)
			(size 0 0)
			(layers "F.Cu" "F.Mask" "F.Paste")
			(net "P12V_NIC6_CO_SS")
		)
		(pad "2" smd circle
			(at 0.40005 0 90)
			(size 0 0)
			(layers "F.Cu" "F.Mask" "F.Paste")
			(net "GND")
		)
	)
	(footprint ""
		(layer "F.Cu")
		(at 411.97784 -113.251742)
		(property "Reference" "R392"
			(at 0 0 0)
			(layer "F.SilkS")
			(hide yes)
			(effects
				(font
					(size 1.27 1.27)
				)
			)
		)
		(property "Value" ""
			(at 0 0 0)
			(layer "F.Fab")
			(effects
				(font
					(size 1.27 1.27)
				)
			)
		)
		(duplicate_pad_numbers_are_jumpers no)
		(fp_line
			(start -0.7874 -0.4064)
			(end 0.7874 -0.4064)
			(stroke
				(width 0.1524)
				(type default)
			)
			(layer "F.SilkS")
		)
		(fp_line
			(start -0.7874 0.4064)
			(end -0.7874 -0.4064)
			(stroke
				(width 0.1524)
				(type default)
			)
			(layer "F.SilkS")
		)
		(fp_line
			(start 0.7874 -0.4064)
			(end 0.7874 0.4064)
			(stroke
				(width 0.1524)
				(type default)
			)
			(layer "F.SilkS")
		)
		(fp_line
			(start 0.7874 0.4064)
			(end -0.7874 0.4064)
			(stroke
				(width 0.1524)
				(type default)
			)
			(layer "F.SilkS")
		)
		(fp_line
			(start -0.67945 -0.305054)
			(end -0.12065 -0.305054)
			(stroke
				(width 0.1)
				(type default)
			)
			(layer "F.Fab")
		)
		(fp_line
			(start -0.67945 0.3048)
			(end -0.67945 -0.305054)
			(stroke
				(width 0.1)
				(type default)
			)
			(layer "F.Fab")
		)
		(fp_line
			(start -0.12065 -0.305054)
			(end -0.12065 -0.2794)
			(stroke
				(width 0.1)
				(type default)
			)
			(layer "F.Fab")
		)
		(fp_line
			(start -0.12065 -0.2794)
			(end 0.12065 -0.2794)
			(stroke
				(width 0.1)
				(type default)
			)
			(layer "F.Fab")
		)
		(fp_line
			(start -0.12065 0.2794)
			(end -0.12065 0.3048)
			(stroke
				(width 0.1)
				(type default)
			)
			(layer "F.Fab")
		)
		(fp_line
			(start -0.12065 0.3048)
			(end -0.67945 0.3048)
			(stroke
				(width 0.1)
				(type default)
			)
			(layer "F.Fab")
		)
		(fp_line
			(start 0.120396 0.2794)
			(end -0.12065 0.2794)
			(stroke
				(width 0.1)
				(type default)
			)
			(layer "F.Fab")
		)
		(fp_line
			(start 0.120396 0.3048)
			(end 0.120396 0.2794)
			(stroke
				(width 0.1)
				(type default)
			)
			(layer "F.Fab")
		)
		(fp_line
			(start 0.12065 -0.3048)
			(end 0.67945 -0.3048)
			(stroke
				(width 0.1)
				(type default)
			)
			(layer "F.Fab")
		)
		(fp_line
			(start 0.12065 -0.2794)
			(end 0.12065 -0.3048)
			(stroke
				(width 0.1)
				(type default)
			)
			(layer "F.Fab")
		)
		(fp_line
			(start 0.67945 -0.3048)
			(end 0.67945 0.3048)
			(stroke
				(width 0.1)
				(type default)
			)
			(layer "F.Fab")
		)
		(fp_line
			(start 0.67945 0.3048)
			(end 0.120396 0.3048)
			(stroke
				(width 0.1)
				(type default)
			)
			(layer "F.Fab")
		)
		(pad "1" smd circle
			(at -0.40005 0)
			(size 0 0)
			(layers "F.Cu" "F.Mask" "F.Paste")
			(net "RST_SMB_NIC7_MUX_ISO_N")
		)
		(pad "2" smd circle
			(at 0.40005 0)
			(size 0 0)
			(layers "F.Cu" "F.Mask" "F.Paste")
			(net "P3V3_NIC7")
		)
	)
)
